# S9S_MB_2U (Grand Teton) — schematic netlist excerpt (pin names and nets, part order shuffled) for the footprints in the layout excerpt that follows; sources: Cadence DE-HDL packaged netlist, KiCad conversion of 03242023_DA0F0TMBIJ0_F0T_Motherboard_J_brd_V01_OCP.brd

R4021  Q_RES  33.2 1% CHIP  pkg 0402LF  page 226 : A = PWRGD_CPUPWRGD_LVC2_R ; B = PWRGD_CPUPWRGD_LVC2_R1
C2033  Q_CAP  0.1UF 25V 10% X7R  pkg 0402  page 152 : A = P3V3_AUX_USB_HUB ; B = GND

(kicad_pcb
	(version 20260206)
	(generator "pcbnew")
	(generator_version "10.0")
	(general
		(thickness 1.6)
		(legacy_teardrops no)
	)
	(paper "A4")
	(title_block
		(title "03242023_DA0F0TMBIJ0_F0T_Motherboard_J_brd_V01_OCP.brd")
		(comment 1 "Grand Teton / footprints 5017-5018 of 6105")
	)
	(layers
		(0 "F.Cu" signal "TOP")
		(4 "In1.Cu" signal "GND")
		(6 "In2.Cu" signal "IN1")
		(8 "In3.Cu" signal "GND1")
		(10 "In4.Cu" signal "IN2")
		(12 "In5.Cu" signal "GND2")
		(14 "In6.Cu" signal "IN3")
		(16 "In7.Cu" signal "GND3")
		(18 "In8.Cu" signal "VCC")
		(20 "In9.Cu" signal "VCC1")
		(22 "In10.Cu" signal "GND4")
		(24 "In11.Cu" signal "IN4")
		(26 "In12.Cu" signal "GND5")
		(28 "In13.Cu" signal "IN5")
		(30 "In14.Cu" signal "GND6")
		(32 "In15.Cu" signal "IN6")
		(34 "In16.Cu" signal "GND7")
		(2 "B.Cu" signal "BOTTOM")
		(9 "F.Adhes" user "F.Adhesive")
		(11 "B.Adhes" user "B.Adhesive")
		(13 "F.Paste" user "Package Geometry/Pastemask Top")
		(15 "B.Paste" user "Package Geometry/Pastemask Bottom")
		(5 "F.SilkS" user "Ref Des/Silkscreen Top")
		(7 "B.SilkS" user "Ref Des/Silkscreen Bottom")
		(1 "F.Mask" user "Board Geometry/Soldermask Top")
		(3 "B.Mask" user "Board Geometry/Soldermask Bottom")
		(17 "Dwgs.User" user "User.Drawings")
		(19 "Cmts.User" user "User.Comments")
		(21 "Eco1.User" user "User.Eco1")
		(23 "Eco2.User" user "User.Eco2")
		(25 "Edge.Cuts" user "Board Geometry/Outline")
		(27 "Margin" user)
		(31 "F.CrtYd" user "Package Geometry/Place Bound Top")
		(29 "B.CrtYd" user "Package Geometry/Place Bound Bottom")
		(35 "F.Fab" user "Ref Des/Assembly Top")
		(33 "B.Fab" user "Ref Des/Assembly Bottom")
	)
	(footprint ""
		(layer "B.Cu")
		(at 12.003532 -99.925632 180)
		(property "Reference" "C2033"
			(at 0 0 0)
			(layer "B.SilkS")
			(hide yes)
			(effects
				(font
					(size 1.27 1.27)
				)
				(justify mirror)
			)
		)
		(property "Value" ""
			(at 0 0 0)
			(layer "B.Fab")
			(effects
				(font
					(size 1.27 1.27)
				)
				(justify mirror)
			)
		)
		(duplicate_pad_numbers_are_jumpers no)
		(fp_line
			(start 0.7874 0.4064)
			(end 0.7874 -0.4064)
			(stroke
				(width 0.1524)
				(type default)
			)
			(layer "B.SilkS")
		)
		(fp_line
			(start 0.7874 -0.4064)
			(end -0.7874 -0.4064)
			(stroke
				(width 0.1524)
				(type default)
			)
			(layer "B.SilkS")
		)
		(fp_line
			(start -0.7874 0.4064)
			(end 0.7874 0.4064)
			(stroke
				(width 0.1524)
				(type default)
			)
			(layer "B.SilkS")
		)
		(fp_line
			(start -0.7874 -0.4064)
			(end -0.7874 0.4064)
			(stroke
				(width 0.1524)
				(type default)
			)
			(layer "B.SilkS")
		)
		(fp_line
			(start 0.67945 0.3048)
			(end 0.67945 -0.305054)
			(stroke
				(width 0.1)
				(type default)
			)
			(layer "B.Fab")
		)
		(fp_line
			(start 0.67945 -0.305054)
			(end 0.12065 -0.305054)
			(stroke
				(width 0.1)
				(type default)
			)
			(layer "B.Fab")
		)
		(fp_line
			(start 0.12065 0.3048)
			(end 0.67945 0.3048)
			(stroke
				(width 0.1)
				(type default)
			)
			(layer "B.Fab")
		)
		(fp_line
			(start 0.12065 0.2794)
			(end 0.12065 0.3048)
			(stroke
				(width 0.1)
				(type default)
			)
			(layer "B.Fab")
		)
		(fp_line
			(start 0.12065 -0.2794)
			(end -0.12065 -0.2794)
			(stroke
				(width 0.1)
				(type default)
			)
			(layer "B.Fab")
		)
		(fp_line
			(start 0.12065 -0.305054)
			(end 0.12065 -0.2794)
			(stroke
				(width 0.1)
				(type default)
			)
			(layer "B.Fab")
		)
		(fp_line
			(start -0.120396 0.3048)
			(end -0.120396 0.2794)
			(stroke
				(width 0.1)
				(type default)
			)
			(layer "B.Fab")
		)
		(fp_line
			(start -0.120396 0.2794)
			(end 0.12065 0.2794)
			(stroke
				(width 0.1)
				(type default)
			)
			(layer "B.Fab")
		)
		(fp_line
			(start -0.12065 -0.2794)
			(end -0.12065 -0.3048)
			(stroke
				(width 0.1)
				(type default)
			)
			(layer "B.Fab")
		)
		(fp_line
			(start -0.12065 -0.3048)
			(end -0.67945 -0.3048)
			(stroke
				(width 0.1)
				(type default)
			)
			(layer "B.Fab")
		)
		(fp_line
			(start -0.67945 0.3048)
			(end -0.120396 0.3048)
			(stroke
				(width 0.1)
				(type default)
			)
			(layer "B.Fab")
		)
		(fp_line
			(start -0.67945 -0.3048)
			(end -0.67945 0.3048)
			(stroke
				(width 0.1)
				(type default)
			)
			(layer "B.Fab")
		)
		(pad "1" smd circle
			(at 0.40005 0)
			(size 0 0)
			(layers "B.Cu" "B.Mask" "B.Paste")
			(net "P3V3_AUX_USB_HUB")
		)
		(pad "2" smd circle
			(at -0.40005 0)
			(size 0 0)
			(layers "B.Cu" "B.Mask" "B.Paste")
			(net "GND")
		)
	)
	(footprint ""
		(layer "B.Cu")
		(at 111.506 -96.738948)
		(property "Reference" "R4021"
			(at 0 0 0)
			(layer "B.SilkS")
			(hide yes)
			(effects
				(font
					(size 1.27 1.27)
				)
				(justify mirror)
			)
		)
		(property "Value" ""
			(at 0 0 0)
			(layer "B.Fab")
			(effects
				(font
					(size 1.27 1.27)
				)
				(justify mirror)
			)
		)
		(duplicate_pad_numbers_are_jumpers no)
		(fp_line
			(start -0.7874 -0.4064)
			(end -0.7874 0.4064)
			(stroke
				(width 0.1524)
				(type default)
			)
			(layer "B.SilkS")
		)
		(fp_line
			(start -0.7874 0.4064)
			(end 0.7874 0.4064)
			(stroke
				(width 0.1524)
				(type default)
			)
			(layer "B.SilkS")
		)
		(fp_line
			(start 0.7874 -0.4064)
			(end -0.7874 -0.4064)
			(stroke
				(width 0.1524)
				(type default)
			)
			(layer "B.SilkS")
		)
		(fp_line
			(start 0.7874 0.4064)
			(end 0.7874 -0.4064)
			(stroke
				(width 0.1524)
				(type default)
			)
			(layer "B.SilkS")
		)
		(fp_line
			(start -0.67945 -0.3048)
			(end -0.67945 0.3048)
			(stroke
				(width 0.1)
				(type default)
			)
			(layer "B.Fab")
		)
		(fp_line
			(start -0.67945 0.3048)
			(end -0.120396 0.3048)
			(stroke
				(width 0.1)
				(type default)
			)
			(layer "B.Fab")
		)
		(fp_line
			(start -0.12065 -0.3048)
			(end -0.67945 -0.3048)
			(stroke
				(width 0.1)
				(type default)
			)
			(layer "B.Fab")
		)
		(fp_line
			(start -0.12065 -0.2794)
			(end -0.12065 -0.3048)
			(stroke
				(width 0.1)
				(type default)
			)
			(layer "B.Fab")
		)
		(fp_line
			(start -0.120396 0.2794)
			(end 0.12065 0.2794)
			(stroke
				(width 0.1)
				(type default)
			)
			(layer "B.Fab")
		)
		(fp_line
			(start -0.120396 0.3048)
			(end -0.120396 0.2794)
			(stroke
				(width 0.1)
				(type default)
			)
			(layer "B.Fab")
		)
		(fp_line
			(start 0.12065 -0.305054)
			(end 0.12065 -0.2794)
			(stroke
				(width 0.1)
				(type default)
			)
			(layer "B.Fab")
		)
		(fp_line
			(start 0.12065 -0.2794)
			(end -0.12065 -0.2794)
			(stroke
				(width 0.1)
				(type default)
			)
			(layer "B.Fab")
		)
		(fp_line
			(start 0.12065 0.2794)
			(end 0.12065 0.3048)
			(stroke
				(width 0.1)
				(type default)
			)
			(layer "B.Fab")
		)
		(fp_line
			(start 0.12065 0.3048)
			(end 0.67945 0.3048)
			(stroke
				(width 0.1)
				(type default)
			)
			(layer "B.Fab")
		)
		(fp_line
			(start 0.67945 -0.305054)
			(end 0.12065 -0.305054)
			(stroke
				(width 0.1)
				(type default)
			)
			(layer "B.Fab")
		)
		(fp_line
			(start 0.67945 0.3048)
			(end 0.67945 -0.305054)
			(stroke
				(width 0.1)
				(type default)
			)
			(layer "B.Fab")
		)
		(pad "1" smd circle
			(at 0.40005 0 180)
			(size 0 0)
			(layers "B.Cu" "B.Mask" "B.Paste")
			(net "PWRGD_CPUPWRGD_LVC2_R")
		)
		(pad "2" smd circle
			(at -0.40005 0 180)
			(size 0 0)
			(layers "B.Cu" "B.Mask" "B.Paste")
			(net "PWRGD_CPUPWRGD_LVC2_R1")
		)
	)
)
